(kicad_pcb
	(version 20241229)
	(generator "pcbnew")
	(generator_version "9.0")
	(general
		(thickness 1.294)
		(legacy_teardrops no)
	)
	(paper "A3")
	(title_block
		(title "Kintex 410T devboard")
		(date "2024-04-03")
		(rev "1.1.2")
		(comment 9 "footprints 248-252 of 975")
	)
	(layers
		(0 "F.Cu" mixed)
		(4 "In1.Cu" power)
		(6 "In2.Cu" power)
		(8 "In3.Cu" mixed)
		(10 "In4.Cu" power)
		(12 "In5.Cu" mixed)
		(14 "In6.Cu" power)
		(16 "In7.Cu" mixed)
		(18 "In8.Cu" power)
		(2 "B.Cu" mixed)
		(9 "F.Adhes" user "F.Adhesive")
		(11 "B.Adhes" user "B.Adhesive")
		(13 "F.Paste" user)
		(15 "B.Paste" user)
		(5 "F.SilkS" user "F.Silkscreen")
		(7 "B.SilkS" user "B.Silkscreen")
		(1 "F.Mask" user)
		(3 "B.Mask" user)
		(17 "Dwgs.User" user "User.Drawings")
		(19 "Cmts.User" user "User.Comments")
		(21 "Eco1.User" user "User.Eco1")
		(23 "Eco2.User" user "User.Eco2")
		(25 "Edge.Cuts" user)
		(27 "Margin" user)
		(31 "F.CrtYd" user "F.Courtyard")
		(29 "B.CrtYd" user "B.Courtyard")
		(35 "F.Fab" user)
		(33 "B.Fab" user)
	)
	(footprint "antmicro-footprints:LED_0603_1608Metric_G"
		(layer "F.Cu")
		(at 266.6 133.9 180)
		(descr "LED SMD 0603 Green")
		(tags "LED SMD 0603 Green")
		(property "Reference" "D29"
			(at -1.1 0.65 0)
			(layer "F.SilkS")
			(effects
				(font
					(size 0.7 0.7)
					(thickness 0.15)
				)
				(justify right bottom)
			)
		)
		(property "Value" "LED_G_0603_KP-1608CGCK"
			(at 0 1.6 0)
			(layer "F.Fab")
			(effects
				(font
					(size 0.7 0.7)
					(thickness 0.15)
				)
				(justify right bottom)
			)
		)
		(property "Description" "LED, Green, SMD, 0603, 20 mA, 2.1 V, 570 nm"
			(at 0 0 180)
			(layer "F.Fab")
			(hide yes)
			(effects
				(font
					(size 1.27 1.27)
					(thickness 0.15)
				)
			)
		)
		(property "Author" "Antmicro"
			(at 533.2 267.8 0)
			(layer "F.Fab")
			(hide yes)
			(effects
				(font
					(size 1 1)
					(thickness 0.15)
				)
			)
		)
		(property "Color" "Green"
			(at 533.2 267.8 0)
			(layer "F.Fab")
			(hide yes)
			(effects
				(font
					(size 1 1)
					(thickness 0.15)
				)
			)
		)
		(property "License" "Apache-2.0"
			(at 533.2 267.8 0)
			(layer "F.Fab")
			(hide yes)
			(effects
				(font
					(size 1 1)
					(thickness 0.15)
				)
			)
		)
		(property "MPN" "KP-1608CGCK"
			(at 533.2 267.8 0)
			(layer "F.Fab")
			(hide yes)
			(effects
				(font
					(size 1 1)
					(thickness 0.15)
				)
			)
		)
		(property "Manufacturer" "Kingbright"
			(at 533.2 267.8 0)
			(layer "F.Fab")
			(hide yes)
			(effects
				(font
					(size 1 1)
					(thickness 0.15)
				)
			)
		)
		(sheetname "USB PHY")
		(sheetfile "usb-phy.kicad_sch")
		(attr smd)
		(fp_line
			(start 0.22 0.35)
			(end -0.22 0.35)
			(stroke
				(width 0.15)
				(type solid)
			)
			(layer "F.SilkS")
		)
		(fp_line
			(start 0.22 -0.35)
			(end -0.22 -0.35)
			(stroke
				(width 0.15)
				(type solid)
			)
			(layer "F.SilkS")
		)
		(fp_line
			(start 0.105328 0.201008)
			(end 0.105328 -0.198992)
			(stroke
				(width 0.1)
				(type solid)
			)
			(layer "F.SilkS")
		)
		(fp_line
			(start 0.105328 0.201008)
			(end -0.094672 0.001008)
			(stroke
				(width 0.1)
				(type solid)
			)
			(layer "F.SilkS")
		)
		(fp_line
			(start 0.105328 0.001008)
			(end 0.24 0.001)
			(stroke
				(width 0.1)
				(type solid)
			)
			(layer "F.SilkS")
		)
		(fp_line
			(start -0.094672 0.201008)
			(end -0.094672 -0.198992)
			(stroke
				(width 0.1)
				(type solid)
			)
			(layer "F.SilkS")
		)
		(fp_line
			(start -0.094672 0.001008)
			(end 0.105328 -0.198992)
			(stroke
				(width 0.1)
				(type solid)
			)
			(layer "F.SilkS")
		)
		(fp_line
			(start -0.094672 0.001008)
			(end -0.24 0.001008)
			(stroke
				(width 0.1)
				(type solid)
			)
			(layer "F.SilkS")
		)
		(fp_line
			(start -1.18 -0.319)
			(end -1.18 0.321)
			(stroke
				(width 0.15)
				(type solid)
			)
			(layer "F.SilkS")
		)
		(fp_rect
			(start 1.25 0.65)
			(end -1.25 -0.65)
			(stroke
				(width 0.05)
				(type solid)
			)
			(fill no)
			(layer "F.CrtYd")
		)
		(fp_line
			(start 0.599 0)
			(end 0.201 0)
			(stroke
				(width 0.15)
				(type solid)
			)
			(layer "F.Fab")
		)
		(fp_line
			(start 0.201 0.2)
			(end 0.201 0)
			(stroke
				(width 0.15)
				(type solid)
			)
			(layer "F.Fab")
		)
		(fp_line
			(start 0.201 0)
			(end 0.201 -0.202)
			(stroke
				(width 0.15)
				(type solid)
			)
			(layer "F.Fab")
		)
		(fp_line
			(start 0.201 -0.202)
			(end -0.101 0)
			(stroke
				(width 0.15)
				(type solid)
			)
			(layer "F.Fab")
		)
		(fp_line
			(start -0.101 0)
			(end 0.201 0.2)
			(stroke
				(width 0.15)
				(type solid)
			)
			(layer "F.Fab")
		)
		(fp_line
			(start -0.199 0.2)
			(end -0.199 0.1)
			(stroke
				(width 0.15)
				(type solid)
			)
			(layer "F.Fab")
		)
		(fp_line
			(start -0.199 0)
			(end -0.597 0)
			(stroke
				(width 0.15)
				(type solid)
			)
			(layer "F.Fab")
		)
		(fp_line
			(start -0.199 -0.202)
			(end -0.199 0.1)
			(stroke
				(width 0.15)
				(type solid)
			)
			(layer "F.Fab")
		)
		(fp_rect
			(start 0.848 0.4)
			(end -0.85 -0.402)
			(stroke
				(width 0.15)
				(type solid)
			)
			(fill no)
			(layer "F.Fab")
		)
		(pad "1" smd roundrect
			(at -0.7 0)
			(size 0.8 1)
			(layers "F.Cu" "F.Mask" "F.Paste")
			(roundrect_rratio 0.2)
			(net 1 "GND")
			(pinfunction "C")
			(pintype "passive")
		)
		(pad "2" smd roundrect
			(at 0.7 0)
			(size 0.8 1)
			(layers "F.Cu" "F.Mask" "F.Paste")
			(roundrect_rratio 0.2)
			(net 793 "Net-(D29-A)")
			(pinfunction "A")
			(pintype "passive")
		)
	)
	(footprint "antmicro-footprints:C_0402_1005Metric"
		(layer "F.Cu")
		(at 151.2 146.65 -90)
		(descr "Capacitor SMD 0402")
		(tags "capacitor SMD 0402")
		(property "Reference" "C346"
			(at -3.65 -0.4 270)
			(layer "F.SilkS")
			(effects
				(font
					(size 0.7 0.7)
					(thickness 0.15)
				)
				(justify right bottom)
			)
		)
		(property "Value" "C_1u_0402"
			(at 0 1.4 90)
			(layer "F.Fab")
			(effects
				(font
					(size 0.7 0.7)
					(thickness 0.15)
				)
				(justify right bottom)
			)
		)
		(property "Description" "SMD Multilayer Ceramic Capacitor, 1 µF, 10 V, 0402 [1005 Metric], ± 10%, X6S, C"
			(at 0 0 270)
			(layer "F.Fab")
			(hide yes)
			(effects
				(font
					(size 1.27 1.27)
					(thickness 0.15)
				)
			)
		)
		(property "Author" "Antmicro"
			(at 4.55 297.85 0)
			(layer "F.Fab")
			(hide yes)
			(effects
				(font
					(size 1 1)
					(thickness 0.15)
				)
			)
		)
		(property "Dielectric" ""
			(at 4.55 297.85 0)
			(layer "F.Fab")
			(hide yes)
			(effects
				(font
					(size 1 1)
					(thickness 0.15)
				)
			)
		)
		(property "License" "Apache-2.0"
			(at 4.55 297.85 0)
			(layer "F.Fab")
			(hide yes)
			(effects
				(font
					(size 1 1)
					(thickness 0.15)
				)
			)
		)
		(property "MPN" "C1005X6S1A105K050BC"
			(at 4.55 297.85 0)
			(layer "F.Fab")
			(hide yes)
			(effects
				(font
					(size 1 1)
					(thickness 0.15)
				)
			)
		)
		(property "Manufacturer" "TDK"
			(at 4.55 297.85 0)
			(layer "F.Fab")
			(hide yes)
			(effects
				(font
					(size 1 1)
					(thickness 0.15)
				)
			)
		)
		(property "Val" "1u"
			(at 4.55 297.85 0)
			(layer "F.Fab")
			(hide yes)
			(effects
				(font
					(size 1 1)
					(thickness 0.15)
				)
			)
		)
		(property "Voltage" ""
			(at 4.55 297.85 0)
			(layer "F.Fab")
			(hide yes)
			(effects
				(font
					(size 1 1)
					(thickness 0.15)
				)
			)
		)
		(sheetname "DC-DC Converters")
		(sheetfile "dc-dc.kicad_sch")
		(attr smd)
		(fp_rect
			(start -0.925 -0.47)
			(end 0.925 0.47)
			(stroke
				(width 0.05)
				(type default)
			)
			(fill no)
			(layer "F.CrtYd")
		)
		(fp_line
			(start -0.494 0.248)
			(end -0.494 -0.25)
			(stroke
				(width 0.15)
				(type solid)
			)
			(layer "F.Fab")
		)
		(fp_line
			(start 0.504 0.248)
			(end -0.494 0.248)
			(stroke
				(width 0.15)
				(type solid)
			)
			(layer "F.Fab")
		)
		(fp_line
			(start -0.494 -0.25)
			(end 0.504 -0.25)
			(stroke
				(width 0.15)
				(type solid)
			)
			(layer "F.Fab")
		)
		(fp_line
			(start 0.504 -0.25)
			(end 0.504 0.248)
			(stroke
				(width 0.15)
				(type solid)
			)
			(layer "F.Fab")
		)
		(pad "1" smd roundrect
			(at -0.48 0 270)
			(size 0.59 0.64)
			(layers "F.Cu" "F.Mask" "F.Paste")
			(roundrect_rratio 0.25)
			(net 1 "GND")
			(pintype "passive")
		)
		(pad "2" smd roundrect
			(at 0.48 0 270)
			(size 0.59 0.64)
			(layers "F.Cu" "F.Mask" "F.Paste")
			(roundrect_rratio 0.25)
			(net 742 "/DC-DC Converters/1V85_VIN")
			(pintype "passive")
		)
	)
	(footprint "antmicro-footprints:Conn_JST_SH_1x4_BM04B-SRSS-TB-LF-SN"
		(layer "F.Cu")
		(at 230.8 133.2 -90)
		(property "Reference" "J7"
			(at -2 1.9 90)
			(layer "F.SilkS")
			(effects
				(font
					(size 0.7 0.7)
					(thickness 0.15)
				)
				(justify right bottom)
			)
		)
		(property "Value" "JST_SH_1x4_BM04B-SRSS-TB-LF-SN"
			(at 0 3.1 90)
			(layer "F.Fab")
			(effects
				(font
					(size 0.7 0.7)
					(thickness 0.15)
				)
				(justify right bottom)
			)
		)
		(property "Description" "Pin Header, Top Entry, Wire-to-Board, 1 mm, 1 Rows, 4 Contacts, Surface Mount, SR"
			(at 0 0 270)
			(layer "F.Fab")
			(hide yes)
			(effects
				(font
					(size 1.27 1.27)
					(thickness 0.15)
				)
			)
		)
		(property "Author" "Antmicro"
			(at 97.6 364 0)
			(layer "F.Fab")
			(hide yes)
			(effects
				(font
					(size 1 1)
					(thickness 0.15)
				)
			)
		)
		(property "License" "Apache-2.0"
			(at 97.6 364 0)
			(layer "F.Fab")
			(hide yes)
			(effects
				(font
					(size 1 1)
					(thickness 0.15)
				)
			)
		)
		(property "MPN" "BM04B-SRSS-TB(LF)(SN) "
			(at 97.6 364 0)
			(layer "F.Fab")
			(hide yes)
			(effects
				(font
					(size 1 1)
					(thickness 0.15)
				)
			)
		)
		(property "Manufacturer" "JST Automotive Connectors"
			(at 97.6 364 0)
			(layer "F.Fab")
			(hide yes)
			(effects
				(font
					(size 1 1)
					(thickness 0.15)
				)
			)
		)
		(sheetname "User GPIO + LED + button + DIP switch")
		(sheetfile "user-gpio.kicad_sch")
		(attr smd)
		(fp_line
			(start -1.125 2.999)
			(end -1.125 2.201)
			(stroke
				(width 0.15)
				(type solid)
			)
			(layer "F.SilkS")
		)
		(fp_line
			(start -0.251 2.999)
			(end -1.125 2.999)
			(stroke
				(width 0.15)
				(type solid)
			)
			(layer "F.SilkS")
		)
		(fp_line
			(start 1.774 -1.7)
			(end 1.774 1.702)
			(stroke
				(width 0.15)
				(type solid)
			)
			(layer "F.SilkS")
		)
		(fp_line
			(start -1.125 -2.999)
			(end -1.125 -2.201)
			(stroke
				(width 0.15)
				(type solid)
			)
			(layer "F.SilkS")
		)
		(fp_line
			(start -0.251 -2.999)
			(end -1.125 -2.999)
			(stroke
				(width 0.15)
				(type solid)
			)
			(layer "F.SilkS")
		)
		(fp_circle
			(center -1.6 -2.1)
			(end -1.55 -2.1)
			(stroke
				(width 0.15)
				(type solid)
			)
			(fill yes)
			(layer "F.SilkS")
		)
		(fp_rect
			(start -2.05 -3.95)
			(end 2.05 3.95)
			(stroke
				(width 0.05)
				(type solid)
			)
			(fill no)
			(layer "F.CrtYd")
		)
		(fp_rect
			(start -1.8 -3)
			(end 1.8 3)
			(stroke
				(width 0.15)
				(type solid)
			)
			(fill no)
			(layer "F.Fab")
		)
		(pad "1" smd roundrect
			(at -1.45 -1.5 180)
			(size 0.6 1.55)
			(layers "F.Cu" "F.Mask" "F.Paste")
			(roundrect_rratio 0.25)
			(net 1 "GND")
			(pinfunction "Pin_1")
			(pintype "passive")
		)
		(pad "2" smd roundrect
			(at -1.45 -0.5 180)
			(size 0.6 1.55)
			(layers "F.Cu" "F.Mask" "F.Paste")
			(roundrect_rratio 0.25)
			(net 703 "+5V")
			(pinfunction "Pin_2")
			(pintype "passive")
		)
		(pad "3" smd roundrect
			(at -1.45 0.5 180)
			(size 0.6 1.55)
			(layers "F.Cu" "F.Mask" "F.Paste")
			(roundrect_rratio 0.25)
			(net 30 "unconnected-(J7-Pin_3-Pad3)")
			(pinfunction "Pin_3")
			(pintype "passive+no_connect")
		)
		(pad "4" smd roundrect
			(at -1.45 1.5 180)
			(size 0.6 1.55)
			(layers "F.Cu" "F.Mask" "F.Paste")
			(roundrect_rratio 0.25)
			(net 801 "/User GPIO + LED + button + DIP switch/FAN_PWM_PIN")
			(pinfunction "Pin_4")
			(pintype "passive")
		)
		(pad "MP" smd roundrect
			(at 1.075 -2.8 180)
			(size 1.2 1.8)
			(layers "F.Cu" "F.Mask" "F.Paste")
			(roundrect_rratio 0.25)
			(net 1 "GND")
			(pinfunction "MP")
			(pintype "passive")
		)
		(pad "MP" smd roundrect
			(at 1.075 2.8 180)
			(size 1.2 1.8)
			(layers "F.Cu" "F.Mask" "F.Paste")
			(roundrect_rratio 0.25)
			(net 1 "GND")
			(pinfunction "MP")
			(pintype "passive")
		)
	)
	(footprint "antmicro-footprints:C_1206_3216Metric"
		(layer "F.Cu")
		(at 193.71 177.039 -90)
		(descr "Capacitor SMD 1206")
		(tags "capacitor SMD 1206")
		(property "Reference" "C201"
			(at -4.689 -2.14 225)
			(layer "F.SilkS")
			(effects
				(font
					(size 0.7 0.7)
					(thickness 0.15)
				)
				(justify right bottom)
			)
		)
		(property "Value" "C_47u_16V_1206"
			(at 0 2.1 90)
			(layer "F.Fab")
			(effects
				(font
					(size 0.7 0.7)
					(thickness 0.15)
				)
				(justify right bottom)
			)
		)
		(property "Description" "SMD Multilayer Ceramic Capacitor, 47 µF, 16 V, 1206 [3216 Metric], ± 20%, X5R, C"
			(at 0 0 270)
			(layer "F.Fab")
			(hide yes)
			(effects
				(font
					(size 1.27 1.27)
					(thickness 0.15)
				)
			)
		)
		(property "Author" "Antmicro"
			(at 16.671 370.749 0)
			(layer "F.Fab")
			(hide yes)
			(effects
				(font
					(size 1 1)
					(thickness 0.15)
				)
			)
		)
		(property "Dielectric" "X5R"
			(at 16.671 370.749 0)
			(layer "F.Fab")
			(hide yes)
			(effects
				(font
					(size 1 1)
					(thickness 0.15)
				)
			)
		)
		(property "License" "Apache-2.0"
			(at 16.671 370.749 0)
			(layer "F.Fab")
			(hide yes)
			(effects
				(font
					(size 1 1)
					(thickness 0.15)
				)
			)
		)
		(property "MPN" "C3216X5R1C476M160AB"
			(at 16.671 370.749 0)
			(layer "F.Fab")
			(hide yes)
			(effects
				(font
					(size 1 1)
					(thickness 0.15)
				)
			)
		)
		(property "Manufacturer" "TDK"
			(at 16.671 370.749 0)
			(layer "F.Fab")
			(hide yes)
			(effects
				(font
					(size 1 1)
					(thickness 0.15)
				)
			)
		)
		(property "Val" "47u"
			(at 16.671 370.749 0)
			(layer "F.Fab")
			(hide yes)
			(effects
				(font
					(size 1 1)
					(thickness 0.15)
				)
			)
		)
		(property "Voltage" "16V"
			(at 16.671 370.749 0)
			(layer "F.Fab")
			(hide yes)
			(effects
				(font
					(size 1 1)
					(thickness 0.15)
				)
			)
		)
		(sheetname "Power supply")
		(sheetfile "power-supply.kicad_sch")
		(attr smd)
		(fp_line
			(start 0.8 0.901)
			(end -0.8 0.901)
			(stroke
				(width 0.15)
				(type solid)
			)
			(layer "F.SilkS")
		)
		(fp_line
			(start 0.8 -0.899)
			(end -0.8 -0.899)
			(stroke
				(width 0.15)
				(type solid)
			)
			(layer "F.SilkS")
		)
		(fp_rect
			(start -2.325 -1.15)
			(end 2.325 1.15)
			(stroke
				(width 0.05)
				(type default)
			)
			(fill no)
			(layer "F.CrtYd")
		)
		(fp_rect
			(start -1.6 -0.799)
			(end 1.6 0.801)
			(stroke
				(width 0.15)
				(type solid)
			)
			(fill no)
			(layer "F.Fab")
		)
		(pad "1" smd roundrect
			(at -1.5 0.001 270)
			(size 1.15 1.8)
			(layers "F.Cu" "F.Mask" "F.Paste")
			(roundrect_rratio 0.25)
			(net 1 "GND")
			(pintype "passive")
		)
		(pad "2" smd roundrect
			(at 1.5 0.001 270)
			(size 1.15 1.8)
			(layers "F.Cu" "F.Mask" "F.Paste")
			(roundrect_rratio 0.25)
			(net 956 "/DC-DC Converters/POE_DC")
			(pintype "passive")
		)
	)
	(footprint "antmicro-footprints:R_0402_1005Metric"
		(layer "F.Cu")
		(at 178.8 77.745 -90)
		(descr "Resistor SMD 0402")
		(tags "resistor SMD 0402")
		(property "Reference" "R7"
			(at 2.355 -0.4 270)
			(layer "F.SilkS")
			(effects
				(font
					(size 0.7 0.7)
					(thickness 0.15)
				)
				(justify left bottom)
			)
		)
		(property "Value" "R_10k_0402"
			(at 0 1.4 270)
			(layer "F.Fab")
			(effects
				(font
					(size 0.7 0.7)
					(thickness 0.15)
				)
				(justify left bottom)
			)
		)
		(property "Description" "SMD Chip Resistor, 10 kohm, ± 1%, 62.5 mW, 0402 [1005 Metric], Thick Film, General Purpose"
			(at 0 0 270)
			(layer "F.Fab")
			(hide yes)
			(effects
				(font
					(size 1.27 1.27)
					(thickness 0.15)
				)
			)
		)
		(property "Author" "Antmicro"
			(at 101.055 256.545 0)
			(layer "F.Fab")
			(hide yes)
			(effects
				(font
					(size 1 1)
					(thickness 0.15)
				)
			)
		)
		(property "License" "Apache-2.0"
			(at 101.055 256.545 0)
			(layer "F.Fab")
			(hide yes)
			(effects
				(font
					(size 1 1)
					(thickness 0.15)
				)
			)
		)
		(property "MPN" "CR0402-FX-1002GLF"
			(at 101.055 256.545 0)
			(layer "F.Fab")
			(hide yes)
			(effects
				(font
					(size 1 1)
					(thickness 0.15)
				)
			)
		)
		(property "Manufacturer" "Bourns"
			(at 101.055 256.545 0)
			(layer "F.Fab")
			(hide yes)
			(effects
				(font
					(size 1 1)
					(thickness 0.15)
				)
			)
		)
		(property "Tolerance" "1%"
			(at 101.055 256.545 0)
			(layer "F.Fab")
			(hide yes)
			(effects
				(font
					(size 1 1)
					(thickness 0.15)
				)
			)
		)
		(property "Val" "10k"
			(at 101.055 256.545 0)
			(layer "F.Fab")
			(hide yes)
			(effects
				(font
					(size 1 1)
					(thickness 0.15)
				)
			)
		)
		(sheetname "FPGA Config")
		(sheetfile "fpga-config.kicad_sch")
		(attr smd)
		(fp_rect
			(start -0.925 -0.47)
			(end 0.925 0.47)
			(stroke
				(width 0.05)
				(type default)
			)
			(fill no)
			(layer "F.CrtYd")
		)
		(fp_rect
			(start -0.5 -0.25)
			(end 0.5 0.25)
			(stroke
				(width 0.15)
				(type solid)
			)
			(fill no)
			(layer "F.Fab")
		)
		(pad "1" smd roundrect
			(at -0.48 0 270)
			(size 0.59 0.64)
			(layers "F.Cu" "F.Mask" "F.Paste")
			(roundrect_rratio 0.25)
			(net 301 "/FPGA Config/PROGRAM_B")
			(pintype "passive")
		)
		(pad "2" smd roundrect
			(at 0.48 0 270)
			(size 0.59 0.64)
			(layers "F.Cu" "F.Mask" "F.Paste")
			(roundrect_rratio 0.25)
			(net 24 "+3V3")
			(pintype "passive")
		)
	)
)
